(kicad_pcb
	(version 20260206)
	(generator "pcbnew")
	(generator_version "10.0")
	(general
		(thickness 1.21888)
		(legacy_teardrops no)
	)
	(paper "A4")
	(title_block
		(title "timecard-v9 — TimeCard-DC-V9_EXP.PcbDoc")
		(comment 1 "Time Appliance Project (Time Card) / footprints 102-108 of 402")
	)
	(layers
		(0 "F.Cu" signal "TOP")
		(4 "In1.Cu" signal "SGND")
		(6 "In2.Cu" signal "IN1")
		(8 "In3.Cu" signal "IN2")
		(10 "In4.Cu" signal "SGND1")
		(2 "B.Cu" signal "BOTTOM")
		(9 "F.Adhes" user "F.Adhesive")
		(11 "B.Adhes" user "B.Adhesive")
		(13 "F.Paste" user "Top Paste")
		(15 "B.Paste" user "Bottom Paste")
		(5 "F.SilkS" user "Top Overlay")
		(7 "B.SilkS" user "Bottom Overlay")
		(1 "F.Mask" user "Top Solder")
		(3 "B.Mask" user "Bottom Solder")
		(17 "Dwgs.User" user "User.Drawings")
		(19 "Cmts.User" user "User.Comments")
		(21 "Eco1.User" user "User.Eco1")
		(23 "Eco2.User" user "User.Eco2")
		(25 "Edge.Cuts" user)
		(27 "Margin" user)
		(31 "F.CrtYd" user "Top Courtyard")
		(29 "B.CrtYd" user "Bottom Courtyard")
		(35 "F.Fab" user "Top Component Center")
		(33 "B.Fab" user "Bottom Component Center")
	)
	(footprint "Vault:RESC1005X40X25LL05T10"
		(layer "F.Cu")
		(at 113.9216 52.2162 90)
		(property "Reference" "R147"
			(at 0.0032 7.626931 90)
			(unlocked yes)
			(layer "F.SilkS")
			(effects
				(font
					(size 0.762 0.762)
					(thickness 0.2032)
				)
			)
		)
		(property "Value" "49.9_1%_0402"
			(at -2.579871 8.798265 0)
			(unlocked yes)
			(layer "F.SilkS")
			(hide yes)
			(effects
				(font
					(size 0.762 0.762)
					(thickness 0.2032)
				)
			)
		)
		(sheetname "11-M2_RCB_MUX")
		(sheetfile "11-M2_RCB_MUX.kicad_sch")
		(duplicate_pad_numbers_are_jumpers no)
		(pad "1" smd rect
			(at -0.375 0 180)
			(size 0.45 0.5)
			(layers "F.Cu" "F.Mask" "F.Paste")
			(net "NetR147_1")
		)
		(pad "2" smd rect
			(at 0.375 0 180)
			(size 0.45 0.5)
			(layers "F.Cu" "F.Mask" "F.Paste")
			(net "GPS1_TP2")
		)
	)
	(footprint "Vault:FP-DO-214AB_SMC_J-Bend-MFG"
		(layer "F.Cu")
		(at 215.3216 71.5162 180)
		(property "Reference" "D23"
			(at 5.873079 -0.0714 90)
			(unlocked yes)
			(layer "F.SilkS")
			(effects
				(font
					(size 0.762 0.762)
					(thickness 0.2286)
				)
			)
		)
		(property "Value" "SMDJ12A"
			(at -6.847071 2.1193 90)
			(unlocked yes)
			(layer "F.SilkS")
			(hide yes)
			(effects
				(font
					(size 0.762 0.762)
					(thickness 0.2286)
				)
			)
		)
		(sheetname "03-POWER")
		(sheetfile "03-POWER.kicad_sch")
		(duplicate_pad_numbers_are_jumpers no)
		(fp_line
			(start 3.555 3.11)
			(end -3.555 3.11)
			(stroke
				(width 0.2)
				(type solid)
			)
			(layer "F.SilkS")
		)
		(fp_line
			(start 3.555 2.025)
			(end 3.555 3.11)
			(stroke
				(width 0.2)
				(type solid)
			)
			(layer "F.SilkS")
		)
		(fp_line
			(start 3.555 -3.11)
			(end 3.555 -2.025)
			(stroke
				(width 0.2)
				(type solid)
			)
			(layer "F.SilkS")
		)
		(fp_line
			(start 3.555 -3.11)
			(end -3.555 -3.11)
			(stroke
				(width 0.2)
				(type solid)
			)
			(layer "F.SilkS")
		)
		(fp_line
			(start -3.555 2.025)
			(end -3.555 3.11)
			(stroke
				(width 0.2)
				(type solid)
			)
			(layer "F.SilkS")
		)
		(fp_line
			(start -3.555 -3.11)
			(end -3.555 -2.025)
			(stroke
				(width 0.2)
				(type solid)
			)
			(layer "F.SilkS")
		)
		(fp_circle
			(center -5.05 0)
			(end -5.05 0.125)
			(stroke
				(width 0.25)
				(type solid)
			)
			(fill no)
			(layer "F.SilkS")
		)
		(fp_line
			(start 4.6 3.21)
			(end -4.6 3.21)
			(stroke
				(width 0.2)
				(type solid)
			)
			(layer "F.CrtYd")
		)
		(fp_line
			(start 4.6 -3.21)
			(end 4.6 3.21)
			(stroke
				(width 0.2)
				(type solid)
			)
			(layer "F.CrtYd")
		)
		(fp_line
			(start 4.6 -3.21)
			(end -4.6 -3.21)
			(stroke
				(width 0.2)
				(type solid)
			)
			(layer "F.CrtYd")
		)
		(fp_line
			(start -4.6 -3.21)
			(end -4.6 3.21)
			(stroke
				(width 0.2)
				(type solid)
			)
			(layer "F.CrtYd")
		)
		(fp_line
			(start 4.6 3.21)
			(end -4.6 3.21)
			(stroke
				(width 0.2)
				(type solid)
			)
			(layer "F.Fab")
		)
		(fp_line
			(start 4.6 -3.21)
			(end 4.6 3.21)
			(stroke
				(width 0.2)
				(type solid)
			)
			(layer "F.Fab")
		)
		(fp_line
			(start 4.6 -3.21)
			(end -4.6 -3.21)
			(stroke
				(width 0.2)
				(type solid)
			)
			(layer "F.Fab")
		)
		(fp_line
			(start 0.5 0)
			(end -0.5 0)
			(stroke
				(width 0.1)
				(type solid)
			)
			(layer "F.Fab")
		)
		(fp_line
			(start 0 -0.5)
			(end 0 0.5)
			(stroke
				(width 0.1)
				(type solid)
			)
			(layer "F.Fab")
		)
		(fp_line
			(start -4.6 -3.21)
			(end -4.6 3.21)
			(stroke
				(width 0.2)
				(type solid)
			)
			(layer "F.Fab")
		)
		(fp_text user "${REFERENCE}"
			(at -0.00001 0.09602 180)
			(unlocked yes)
			(layer "F.Fab")
			(effects
				(font
					(face "Arial")
					(size 0.63 0.63)
					(thickness 0.1)
				)
				(justify left bottom)
			)
		)
		(pad "1" smd rect
			(at -3.3 0 180)
			(size 2.4 3.3)
			(layers "F.Cu" "F.Mask" "F.Paste")
			(net "+12V_SENS")
			(solder_mask_margin 0)
			(solder_paste_margin 0)
		)
		(pad "2" smd rect
			(at 3.3 0 180)
			(size 2.4 3.3)
			(layers "F.Cu" "F.Mask" "F.Paste")
			(net "GND")
			(solder_mask_margin 0)
			(solder_paste_margin 0)
		)
	)
	(footprint "Vault:RESC1005X40X25NL05T05"
		(layer "F.Cu")
		(at 150.8216 128.6162)
		(property "Reference" "R91"
			(at -2.171395 -0.073069 0)
			(unlocked yes)
			(layer "F.SilkS")
			(effects
				(font
					(size 0.762 0.762)
					(thickness 0.2286)
				)
			)
		)
		(property "Value" "27_1%_0402"
			(at -2.732271 7.37632 270)
			(unlocked yes)
			(layer "F.SilkS")
			(hide yes)
			(effects
				(font
					(size 0.762 0.762)
					(thickness 0.2286)
				)
			)
		)
		(sheetname "09-USBUart_PPSMUX_UARTMUX")
		(sheetfile "09-USBUart_PPSMUX_UARTMUX.kicad_sch")
		(duplicate_pad_numbers_are_jumpers no)
		(pad "1" smd rect
			(at -0.45 0 90)
			(size 0.55 0.55)
			(layers "F.Cu" "F.Mask" "F.Paste")
			(net "GPS2_TX_FPGA")
		)
		(pad "2" smd rect
			(at 0.45 0 90)
			(size 0.55 0.55)
			(layers "F.Cu" "F.Mask" "F.Paste")
			(net "NetR91_2")
		)
	)
	(footprint "Vault:RESC1005X40X25NL05T05"
		(layer "F.Cu")
		(at 155.4216 127.3162 -90)
		(property "Reference" "R90"
			(at -2.0714 0.026931 270)
			(unlocked yes)
			(layer "F.SilkS")
			(effects
				(font
					(size 0.762 0.762)
					(thickness 0.2286)
				)
			)
		)
		(property "Value" "27_1%_0402"
			(at -2.732271 7.37632 180)
			(unlocked yes)
			(layer "F.SilkS")
			(hide yes)
			(effects
				(font
					(size 0.762 0.762)
					(thickness 0.2286)
				)
			)
		)
		(sheetname "09-USBUart_PPSMUX_UARTMUX")
		(sheetfile "09-USBUart_PPSMUX_UARTMUX.kicad_sch")
		(duplicate_pad_numbers_are_jumpers no)
		(pad "1" smd rect
			(at -0.45 0)
			(size 0.55 0.55)
			(layers "F.Cu" "F.Mask" "F.Paste")
			(net "FTDI_RX")
		)
		(pad "2" smd rect
			(at 0.45 0)
			(size 0.55 0.55)
			(layers "F.Cu" "F.Mask" "F.Paste")
			(net "NetR90_2")
		)
	)
	(footprint "Vault:RESC1005X40X25NL05T05"
		(layer "F.Cu")
		(at 153.3216 132.2162)
		(property "Reference" "R103"
			(at -0.0714 1.126931 0)
			(unlocked yes)
			(layer "F.SilkS")
			(effects
				(font
					(size 0.762 0.762)
					(thickness 0.2286)
				)
			)
		)
		(property "Value" "DNI_27_1%_0402"
			(at -2.732281 10.296375 270)
			(unlocked yes)
			(layer "F.SilkS")
			(hide yes)
			(effects
				(font
					(size 0.762 0.762)
					(thickness 0.2286)
				)
			)
		)
		(sheetname "09-USBUart_PPSMUX_UARTMUX")
		(sheetfile "09-USBUart_PPSMUX_UARTMUX.kicad_sch")
		(duplicate_pad_numbers_are_jumpers no)
		(pad "1" smd rect
			(at -0.45 0 90)
			(size 0.55 0.55)
			(layers "F.Cu" "F.Mask" "F.Paste")
			(net "GPS2_RX_FPGA")
		)
		(pad "2" smd rect
			(at 0.45 0 90)
			(size 0.55 0.55)
			(layers "F.Cu" "F.Mask" "F.Paste")
			(net "GPS2_RX")
		)
	)
	(footprint "Vault:FP-MYMGK-12-MFG"
		(layer "F.Cu")
		(at 179.5216 92.9162 -90)
		(property "Reference" "U18"
			(at -4.373079 0.3714 0)
			(unlocked yes)
			(layer "F.SilkS")
			(effects
				(font
					(size 0.762 0.762)
					(thickness 0.2286)
				)
			)
		)
		(property "Value" "DNI_MYMGK00506ERSR"
			(at 7.146775 5.234191 270)
			(unlocked yes)
			(layer "F.SilkS")
			(hide yes)
			(effects
				(font
					(size 0.762 0.762)
					(thickness 0.2286)
				)
			)
		)
		(sheetname "03-POWER")
		(sheetfile "03-POWER.kicad_sch")
		(duplicate_pad_numbers_are_jumpers no)
		(fp_line
			(start -3.825 4.575)
			(end -3.825 -4.575)
			(stroke
				(width 0.2)
				(type solid)
			)
			(layer "F.SilkS")
		)
		(fp_line
			(start -3.625 4.575)
			(end -3.825 4.575)
			(stroke
				(width 0.2)
				(type solid)
			)
			(layer "F.SilkS")
		)
		(fp_line
			(start 0.325 4.575)
			(end -0.325 4.575)
			(stroke
				(width 0.2)
				(type solid)
			)
			(layer "F.SilkS")
		)
		(fp_line
			(start 3.825 4.575)
			(end 3.625 4.575)
			(stroke
				(width 0.2)
				(type solid)
			)
			(layer "F.SilkS")
		)
		(fp_line
			(start 3.825 4.575)
			(end 3.825 -4.575)
			(stroke
				(width 0.2)
				(type solid)
			)
			(layer "F.SilkS")
		)
		(fp_line
			(start -3.625 -4.575)
			(end -3.825 -4.575)
			(stroke
				(width 0.2)
				(type solid)
			)
			(layer "F.SilkS")
		)
		(fp_line
			(start 0.325 -4.575)
			(end -0.325 -4.575)
			(stroke
				(width 0.2)
				(type solid)
			)
			(layer "F.SilkS")
		)
		(fp_line
			(start 3.825 -4.575)
			(end 3.625 -4.575)
			(stroke
				(width 0.2)
				(type solid)
			)
			(layer "F.SilkS")
		)
		(fp_circle
			(center -4.575 -3.625)
			(end -4.7 -3.625)
			(stroke
				(width 0.25)
				(type solid)
			)
			(fill no)
			(layer "F.SilkS")
		)
		(fp_line
			(start -4.325 5.075)
			(end -4.325 -5.075)
			(stroke
				(width 0.2)
				(type solid)
			)
			(layer "F.CrtYd")
		)
		(fp_line
			(start 4.325 5.075)
			(end -4.325 5.075)
			(stroke
				(width 0.2)
				(type solid)
			)
			(layer "F.CrtYd")
		)
		(fp_line
			(start 4.325 5.075)
			(end 4.325 -5.075)
			(stroke
				(width 0.2)
				(type solid)
			)
			(layer "F.CrtYd")
		)
		(fp_line
			(start 4.325 -5.075)
			(end -4.325 -5.075)
			(stroke
				(width 0.2)
				(type solid)
			)
			(layer "F.CrtYd")
		)
		(fp_line
			(start -4.325 5.075)
			(end -4.325 -5.075)
			(stroke
				(width 0.2)
				(type solid)
			)
			(layer "F.Fab")
		)
		(fp_line
			(start 4.325 5.075)
			(end -4.325 5.075)
			(stroke
				(width 0.2)
				(type solid)
			)
			(layer "F.Fab")
		)
		(fp_line
			(start 4.325 5.075)
			(end 4.325 -5.075)
			(stroke
				(width 0.2)
				(type solid)
			)
			(layer "F.Fab")
		)
		(fp_line
			(start 0 0.5)
			(end 0 -0.5)
			(stroke
				(width 0.1)
				(type solid)
			)
			(layer "F.Fab")
		)
		(fp_line
			(start 0.5 0)
			(end -0.5 0)
			(stroke
				(width 0.1)
				(type solid)
			)
			(layer "F.Fab")
		)
		(fp_line
			(start 4.325 -5.075)
			(end -4.325 -5.075)
			(stroke
				(width 0.2)
				(type solid)
			)
			(layer "F.Fab")
		)
		(fp_text user "${REFERENCE}"
			(at -0.00001 0.09602 270)
			(unlocked yes)
			(layer "F.Fab")
			(effects
				(font
					(face "Arial")
					(size 0.63 0.63)
					(thickness 0.1)
				)
				(justify left bottom)
			)
		)
		(pad "" smd custom
			(at -1.7 -0.75)
			(size 0.000001 0.000001)
			(layers "F.Cu" "F.Mask" "F.Paste")
			(solder_mask_margin 0)
			(solder_paste_margin 0)
			(thermal_bridge_angle 90)
			(options
				(clearance outline)
				(anchor circle)
			)
			(primitives
				(gr_poly
					(pts
						(xy 0 0) (xy 0 1) (xy 0.9 1) (xy 0.9 0.45) (xy 0.45 0)
					)
					(width 0)
					(fill yes)
				)
			)
		)
		(pad "1" smd rect
			(at -2.75 -3.55 270)
			(size 1 1.4)
			(layers "F.Cu" "F.Mask" "F.Paste")
			(net "+12V")
			(solder_mask_margin 0)
			(solder_paste_margin 0)
		)
		(pad "2" smd rect
			(at -1.2 -3.55 270)
			(size 1 1.4)
			(layers "F.Cu" "F.Mask" "F.Paste")
			(net "+12V")
			(solder_mask_margin 0)
			(solder_paste_margin 0)
		)
		(pad "3" smd rect
			(at -2.75 -1.2 270)
			(size 1 0.9)
			(layers "F.Cu" "F.Mask" "F.Paste")
			(net "GND")
			(solder_mask_margin 0)
			(solder_paste_margin 0)
		)
		(pad "4" smd rect
			(at -2.75 0 270)
			(size 1 0.9)
			(layers "F.Cu" "F.Mask" "F.Paste")
			(net "NetR61_2")
			(solder_mask_margin 0)
			(solder_paste_margin 0)
		)
		(pad "5" smd rect
			(at -2.75 1.2 270)
			(size 1 0.9)
			(layers "F.Cu" "F.Mask" "F.Paste")
			(net "P3V3_SENSE")
			(solder_mask_margin 0)
			(solder_paste_margin 0)
		)
		(pad "6" smd rect
			(at -2.75 3.55 270)
			(size 1 1.4)
			(layers "F.Cu" "F.Mask" "F.Paste")
			(net "P3V3_SENSE")
			(solder_mask_margin 0)
			(solder_paste_margin 0)
		)
		(pad "7" smd rect
			(at -1.2 3.55 270)
			(size 1 1.4)
			(layers "F.Cu" "F.Mask" "F.Paste")
			(net "P3V3_SENSE")
			(solder_mask_margin 0)
			(solder_paste_margin 0)
		)
		(pad "8" smd rect
			(at 1.2 3.55 270)
			(size 1 1.4)
			(layers "F.Cu" "F.Mask" "F.Paste")
			(net "GND")
			(solder_mask_margin 0)
			(solder_paste_margin 0)
		)
		(pad "9" smd rect
			(at 2.75 3.55 270)
			(size 1 1.4)
			(layers "F.Cu" "F.Mask" "F.Paste")
			(net "GND")
			(solder_mask_margin 0)
			(solder_paste_margin 0)
		)
		(pad "10" smd rect
			(at 2.75 1.2 270)
			(size 1 0.9)
			(layers "F.Cu" "F.Mask" "F.Paste")
			(net "GND")
			(solder_mask_margin 0)
			(solder_paste_margin 0)
		)
		(pad "11" smd rect
			(at 2.75 0 270)
			(size 1 0.9)
			(layers "F.Cu" "F.Mask" "F.Paste")
			(net "NetR183_2")
			(solder_mask_margin 0)
			(solder_paste_margin 0)
		)
		(pad "12" smd rect
			(at 2.75 -1.2 270)
			(size 1 0.9)
			(layers "F.Cu" "F.Mask" "F.Paste")
			(net "NetR129_2")
			(solder_mask_margin 0)
			(solder_paste_margin 0)
		)
		(pad "13" smd rect
			(at 2.75 -3.55 270)
			(size 1 1.4)
			(layers "F.Cu" "F.Mask" "F.Paste")
			(net "GND")
			(solder_mask_margin 0)
			(solder_paste_margin 0)
		)
		(pad "14" smd rect
			(at 1.2 -3.55 270)
			(size 1 1.4)
			(layers "F.Cu" "F.Mask" "F.Paste")
			(net "GND")
			(solder_mask_margin 0)
			(solder_paste_margin 0)
		)
		(pad "15" smd circle
			(at -1.15563 -1.16197 270)
			(size 0.74127 0.74127)
			(layers "F.Cu" "F.Mask" "F.Paste")
			(net "GND")
			(solder_mask_margin 0)
			(solder_paste_margin 0)
			(thermal_bridge_angle 90)
		)
		(pad "16" smd rect
			(at -1.2 0 270)
			(size 1 0.9)
			(layers "F.Cu" "F.Mask" "F.Paste")
			(net "GND")
			(solder_mask_margin 0)
			(solder_paste_margin 0)
		)
		(pad "17" smd rect
			(at -1.2 1.2 270)
			(size 1 0.9)
			(layers "F.Cu" "F.Mask" "F.Paste")
			(net "GND")
			(solder_mask_margin 0)
			(solder_paste_margin 0)
		)
		(pad "18" smd rect
			(at 0 -1.2 270)
			(size 1 0.9)
			(layers "F.Cu" "F.Mask" "F.Paste")
			(net "GND")
			(solder_mask_margin 0)
			(solder_paste_margin 0)
		)
		(pad "19" smd rect
			(at 0 0 270)
			(size 1 0.9)
			(layers "F.Cu" "F.Mask" "F.Paste")
			(net "GND")
			(solder_mask_margin 0)
			(solder_paste_margin 0)
		)
		(pad "20" smd rect
			(at 0 1.2 270)
			(size 1 0.9)
			(layers "F.Cu" "F.Mask" "F.Paste")
			(net "GND")
			(solder_mask_margin 0)
			(solder_paste_margin 0)
		)
		(pad "21" smd rect
			(at 1.2 -1.2 270)
			(size 1 0.9)
			(layers "F.Cu" "F.Mask" "F.Paste")
			(net "GND")
			(solder_mask_margin 0)
			(solder_paste_margin 0)
		)
		(pad "22" smd rect
			(at 1.2 0 270)
			(size 1 0.9)
			(layers "F.Cu" "F.Mask" "F.Paste")
			(net "GND")
			(solder_mask_margin 0)
			(solder_paste_margin 0)
		)
		(pad "23" smd rect
			(at 1.2 1.2 270)
			(size 1 0.9)
			(layers "F.Cu" "F.Mask" "F.Paste")
			(net "GND")
			(solder_mask_margin 0)
			(solder_paste_margin 0)
		)
	)
	(footprint "Vault:RESC1005X40X25LL05T10"
		(layer "F.Cu")
		(at 195.9216 120.0162 -90)
		(property "Reference" "R166"
			(at -2.6032 -0.226931 90)
			(unlocked yes)
			(layer "F.SilkS")
			(effects
				(font
					(size 0.762 0.762)
					(thickness 0.2032)
				)
			)
		)
		(property "Value" "DNI_49.9_1%_0402"
			(at -2.579871 11.71832 180)
			(unlocked yes)
			(layer "F.SilkS")
			(hide yes)
			(effects
				(font
					(size 0.762 0.762)
					(thickness 0.2032)
				)
			)
		)
		(sheetname "11-M2_RCB_MUX")
		(sheetfile "11-M2_RCB_MUX.kicad_sch")
		(duplicate_pad_numbers_are_jumpers no)
		(pad "1" smd rect
			(at -0.375 0)
			(size 0.45 0.5)
			(layers "F.Cu" "F.Mask" "F.Paste")
			(net "GPS2_PIN11")
		)
		(pad "2" smd rect
			(at 0.375 0)
			(size 0.45 0.5)
			(layers "F.Cu" "F.Mask" "F.Paste")
			(net "RCB_GPS2_PIN11")
		)
	)
)
